(kicad_pcb
	(version 20260206)
	(generator "pcbnew")
	(generator_version "10.0")
	(general
		(thickness 1.6)
		(legacy_teardrops no)
	)
	(paper "A4")
	(title_block
		(title "pdpb — Lightning_PDPB_BRD.brd")
		(comment 1 "Lightning (Wiwynn / Facebook NVMe JBOF) / footprints 794-800 of 1140")
	)
	(layers
		(0 "F.Cu" signal "TOP")
		(4 "In1.Cu" signal "L2GND")
		(6 "In2.Cu" signal "L3")
		(8 "In3.Cu" signal "L4VCC")
		(10 "In4.Cu" signal "L5VCC")
		(12 "In5.Cu" signal "L6")
		(14 "In6.Cu" signal "L7GND")
		(2 "B.Cu" signal "BOTTOM")
		(9 "F.Adhes" user "F.Adhesive")
		(11 "B.Adhes" user "B.Adhesive")
		(13 "F.Paste" user "Package Geometry/Pastemask Top")
		(15 "B.Paste" user "Package Geometry/Pastemask Bottom")
		(5 "F.SilkS" user "Ref Des/Silkscreen Top")
		(7 "B.SilkS" user "Ref Des/Silkscreen Bottom")
		(1 "F.Mask" user "Board Geometry/Soldermask Top")
		(3 "B.Mask" user "Board Geometry/Soldermask Bottom")
		(17 "Dwgs.User" user "User.Drawings")
		(19 "Cmts.User" user "User.Comments")
		(21 "Eco1.User" user "User.Eco1")
		(23 "Eco2.User" user "User.Eco2")
		(25 "Edge.Cuts" user "Board Geometry/Outline")
		(27 "Margin" user)
		(31 "F.CrtYd" user "Package Geometry/Place Bound Top")
		(29 "B.CrtYd" user "Package Geometry/Place Bound Bottom")
		(35 "F.Fab" user "Ref Des/Assembly Top")
		(33 "B.Fab" user "Ref Des/Assembly Bottom")
	)
	(footprint ""
		(layer "F.Cu")
		(at 8.8138 -476.885 90)
		(property "Reference" "PC1167"
			(at 0 0 90)
			(layer "F.SilkS")
			(hide yes)
			(effects
				(font
					(size 1.27 1.27)
				)
			)
		)
		(property "Value" "SC22U25V6KX-GP-U"
			(at -2.860802 -5.279644 90)
			(unlocked yes)
			(layer "F.Fab")
			(hide yes)
			(effects
				(font
					(size 1.016 1.016)
					(thickness 0.1524)
				)
			)
		)
		(property "Device Type" "C1206-TO0D3H75"
			(at -2.860802 -6.803644 90)
			(unlocked yes)
			(layer "F.Fab")
			(hide yes)
			(effects
				(font
					(size 1.016 1.016)
					(thickness 0.1524)
				)
			)
		)
		(duplicate_pad_numbers_are_jumpers no)
		(fp_line
			(start 1.3081 -2.3749)
			(end 1.3081 2.3749)
			(stroke
				(width 0.1524)
				(type default)
			)
			(layer "F.SilkS")
		)
		(fp_line
			(start -1.3081 -2.3749)
			(end 1.3081 -2.3749)
			(stroke
				(width 0.1524)
				(type default)
			)
			(layer "F.SilkS")
		)
		(fp_line
			(start 1.3081 2.3749)
			(end -1.3081 2.3749)
			(stroke
				(width 0.1524)
				(type default)
			)
			(layer "F.SilkS")
		)
		(fp_line
			(start -1.3081 2.3749)
			(end -1.3081 -2.3749)
			(stroke
				(width 0.1524)
				(type default)
			)
			(layer "F.SilkS")
		)
		(fp_rect
			(start -0.8001 1.6002)
			(end 0.8001 -1.6002)
			(stroke
				(width 0)
				(type default)
			)
			(fill no)
			(layer "F.CrtYd")
		)
		(fp_poly
			(pts
				(xy -1.5621 2.4511) (xy -1.5621 1.6002) (xy 0.8001 1.6002) (xy 0.8001 -1.6002) (xy -0.8001 -1.6002)
				(xy -0.8001 1.5875) (xy -1.5621 1.5875) (xy -1.5621 -2.4511) (xy 1.5621 -2.4511) (xy 1.5621 2.4511)
			)
			(stroke
				(width 0)
				(type default)
			)
			(fill no)
			(layer "F.CrtYd")
		)
		(fp_rect
			(start -1.5621 2.4511)
			(end 1.5621 -2.4511)
			(stroke
				(width 0)
				(type default)
			)
			(fill no)
			(layer "F.Fab")
		)
		(pad "1" smd rect
			(at 0 -1.392936 90)
			(size 2.1082 1.4478)
			(layers "F.Cu" "F.Mask" "F.Paste")
			(net "P12V")
		)
		(pad "2" smd rect
			(at 0 1.392936 90)
			(size 2.1082 1.4478)
			(layers "F.Cu" "F.Mask" "F.Paste")
			(net "GND")
		)
	)
	(footprint ""
		(layer "F.Cu")
		(at 233.807 -241.802158 180)
		(property "Reference" "Q38"
			(at 0 0 180)
			(layer "F.SilkS")
			(hide yes)
			(effects
				(font
					(size 1.27 1.27)
				)
			)
		)
		(property "Value" "2N7002A-7-GP"
			(at 0.127 -8.9662 180)
			(unlocked yes)
			(layer "F.Fab")
			(hide yes)
			(effects
				(font
					(size 1.016 1.016)
					(thickness 0.1524)
				)
			)
		)
		(property "Device Type" "SOT23DGS2D4H48"
			(at 0.127 -10.4902 180)
			(unlocked yes)
			(layer "F.Fab")
			(hide yes)
			(effects
				(font
					(size 1.016 1.016)
					(thickness 0.1524)
				)
			)
		)
		(duplicate_pad_numbers_are_jumpers no)
		(fp_line
			(start 1.651 1.778)
			(end 1.651 -1.778)
			(stroke
				(width 0.1524)
				(type default)
			)
			(layer "F.SilkS")
		)
		(fp_line
			(start 1.651 -1.778)
			(end -1.651 -1.778)
			(stroke
				(width 0.1524)
				(type default)
			)
			(layer "F.SilkS")
		)
		(fp_line
			(start -1.651 1.778)
			(end 1.651 1.778)
			(stroke
				(width 0.1524)
				(type default)
			)
			(layer "F.SilkS")
		)
		(fp_line
			(start -1.651 -1.778)
			(end -1.651 1.778)
			(stroke
				(width 0.1524)
				(type default)
			)
			(layer "F.SilkS")
		)
		(fp_poly
			(pts
				(xy -1.778 1.8796) (xy -1.778 -1.8796) (xy 1.778 -1.8796) (xy 1.778 1.8796)
			)
			(stroke
				(width 0)
				(type default)
			)
			(fill no)
			(layer "F.CrtYd")
		)
		(fp_poly
			(pts
				(xy -1.778 1.8796) (xy -1.778 -1.8796) (xy 1.778 -1.8796) (xy 1.778 1.8796)
			)
			(stroke
				(width 0)
				(type default)
			)
			(fill no)
			(layer "F.Fab")
		)
		(pad "D" smd custom
			(at 0 -0.9525 180)
			(size 0.1905 0.1905)
			(layers "F.Cu" "F.Mask" "F.Paste")
			(net "SSD_ACT_DR2_MOS_N")
			(options
				(clearance outline)
				(anchor circle)
			)
			(primitives
				(gr_poly
					(pts
						(arc
							(start -0.1778 0.5715)
							(mid -0.321484 0.511984)
							(end -0.381 0.3683)
						)
						(arc
							(start -0.381 -0.3683)
							(mid -0.321484 -0.511984)
							(end -0.1778 -0.5715)
						)
						(arc
							(start 0.1778 -0.5715)
							(mid 0.321484 -0.511984)
							(end 0.381 -0.3683)
						)
						(arc
							(start 0.381 0.3683)
							(mid 0.321484 0.511984)
							(end 0.1778 0.5715)
						)
					)
					(width 0)
					(fill yes)
				)
			)
		)
		(pad "G" smd custom
			(at -0.98425 0.9525 180)
			(size 0.1905 0.1905)
			(layers "F.Cu" "F.Mask" "F.Paste")
			(net "ATTN_LED_DR2_AND_R")
			(options
				(clearance outline)
				(anchor circle)
			)
			(primitives
				(gr_poly
					(pts
						(arc
							(start -0.1778 0.5715)
							(mid -0.321484 0.511984)
							(end -0.381 0.3683)
						)
						(arc
							(start -0.381 -0.3683)
							(mid -0.321484 -0.511984)
							(end -0.1778 -0.5715)
						)
						(arc
							(start 0.1778 -0.5715)
							(mid 0.321484 -0.511984)
							(end 0.381 -0.3683)
						)
						(arc
							(start 0.381 0.3683)
							(mid 0.321484 0.511984)
							(end 0.1778 0.5715)
						)
					)
					(width 0)
					(fill yes)
				)
			)
		)
		(pad "S" smd custom
			(at 0.98425 0.9525 180)
			(size 0.1905 0.1905)
			(layers "F.Cu" "F.Mask" "F.Paste")
			(net "SSD_ACT_DR2_R")
			(options
				(clearance outline)
				(anchor circle)
			)
			(primitives
				(gr_poly
					(pts
						(arc
							(start -0.1778 0.5715)
							(mid -0.321484 0.511984)
							(end -0.381 0.3683)
						)
						(arc
							(start -0.381 -0.3683)
							(mid -0.321484 -0.511984)
							(end -0.1778 -0.5715)
						)
						(arc
							(start 0.1778 -0.5715)
							(mid 0.321484 -0.511984)
							(end 0.381 -0.3683)
						)
						(arc
							(start 0.381 0.3683)
							(mid 0.321484 0.511984)
							(end 0.1778 0.5715)
						)
					)
					(width 0)
					(fill yes)
				)
			)
		)
	)
	(footprint ""
		(layer "F.Cu")
		(at 220.726 -241.040158)
		(property "Reference" "Q39"
			(at 0 0 0)
			(layer "F.SilkS")
			(hide yes)
			(effects
				(font
					(size 1.27 1.27)
				)
			)
		)
		(property "Value" "2N7002A-7-GP"
			(at 0.127 -8.9662 0)
			(unlocked yes)
			(layer "F.Fab")
			(hide yes)
			(effects
				(font
					(size 1.016 1.016)
					(thickness 0.1524)
				)
			)
		)
		(property "Device Type" "SOT23DGS2D4H48"
			(at 0.127 -10.4902 0)
			(unlocked yes)
			(layer "F.Fab")
			(hide yes)
			(effects
				(font
					(size 1.016 1.016)
					(thickness 0.1524)
				)
			)
		)
		(duplicate_pad_numbers_are_jumpers no)
		(fp_line
			(start -1.651 -1.778)
			(end -1.651 1.778)
			(stroke
				(width 0.1524)
				(type default)
			)
			(layer "F.SilkS")
		)
		(fp_line
			(start -1.651 1.778)
			(end 1.651 1.778)
			(stroke
				(width 0.1524)
				(type default)
			)
			(layer "F.SilkS")
		)
		(fp_line
			(start 1.651 -1.778)
			(end -1.651 -1.778)
			(stroke
				(width 0.1524)
				(type default)
			)
			(layer "F.SilkS")
		)
		(fp_line
			(start 1.651 1.778)
			(end 1.651 -1.778)
			(stroke
				(width 0.1524)
				(type default)
			)
			(layer "F.SilkS")
		)
		(fp_poly
			(pts
				(xy -1.778 1.8796) (xy -1.778 -1.8796) (xy 1.778 -1.8796) (xy 1.778 1.8796)
			)
			(stroke
				(width 0)
				(type default)
			)
			(fill no)
			(layer "F.CrtYd")
		)
		(fp_poly
			(pts
				(xy -1.778 1.8796) (xy -1.778 -1.8796) (xy 1.778 -1.8796) (xy 1.778 1.8796)
			)
			(stroke
				(width 0)
				(type default)
			)
			(fill no)
			(layer "F.Fab")
		)
		(pad "D" smd custom
			(at 0 -0.9525)
			(size 0.1905 0.1905)
			(layers "F.Cu" "F.Mask" "F.Paste")
			(net "SSD2_CLK0_OE_MOS_N")
			(options
				(clearance outline)
				(anchor circle)
			)
			(primitives
				(gr_poly
					(pts
						(arc
							(start -0.1778 0.5715)
							(mid -0.321484 0.511984)
							(end -0.381 0.3683)
						)
						(arc
							(start -0.381 -0.3683)
							(mid -0.321484 -0.511984)
							(end -0.1778 -0.5715)
						)
						(arc
							(start 0.1778 -0.5715)
							(mid 0.321484 -0.511984)
							(end 0.381 -0.3683)
						)
						(arc
							(start 0.381 0.3683)
							(mid 0.321484 0.511984)
							(end 0.1778 0.5715)
						)
					)
					(width 0)
					(fill yes)
				)
			)
		)
		(pad "G" smd custom
			(at -0.98425 0.9525)
			(size 0.1905 0.1905)
			(layers "F.Cu" "F.Mask" "F.Paste")
			(net "SSD2_CLK0_OE_R_N")
			(options
				(clearance outline)
				(anchor circle)
			)
			(primitives
				(gr_poly
					(pts
						(arc
							(start -0.1778 0.5715)
							(mid -0.321484 0.511984)
							(end -0.381 0.3683)
						)
						(arc
							(start -0.381 -0.3683)
							(mid -0.321484 -0.511984)
							(end -0.1778 -0.5715)
						)
						(arc
							(start 0.1778 -0.5715)
							(mid 0.321484 -0.511984)
							(end 0.381 -0.3683)
						)
						(arc
							(start 0.381 0.3683)
							(mid 0.321484 0.511984)
							(end 0.1778 0.5715)
						)
					)
					(width 0)
					(fill yes)
				)
			)
		)
		(pad "S" smd custom
			(at 0.98425 0.9525)
			(size 0.1905 0.1905)
			(layers "F.Cu" "F.Mask" "F.Paste")
			(net "GND")
			(options
				(clearance outline)
				(anchor circle)
			)
			(primitives
				(gr_poly
					(pts
						(arc
							(start -0.1778 0.5715)
							(mid -0.321484 0.511984)
							(end -0.381 0.3683)
						)
						(arc
							(start -0.381 -0.3683)
							(mid -0.321484 -0.511984)
							(end -0.1778 -0.5715)
						)
						(arc
							(start 0.1778 -0.5715)
							(mid 0.321484 -0.511984)
							(end 0.381 -0.3683)
						)
						(arc
							(start 0.381 0.3683)
							(mid 0.321484 0.511984)
							(end 0.1778 0.5715)
						)
					)
					(width 0)
					(fill yes)
				)
			)
		)
	)
	(footprint ""
		(layer "F.Cu")
		(at 37.719 -297.561 180)
		(property "Reference" "PC1247"
			(at 0 0 180)
			(layer "F.SilkS")
			(hide yes)
			(effects
				(font
					(size 1.27 1.27)
				)
			)
		)
		(property "Value" "SCD1U50V3KX-GP"
			(at 0 -2.8194 180)
			(unlocked yes)
			(layer "F.Fab")
			(hide yes)
			(effects
				(font
					(size 1.016 1.016)
					(thickness 0.1524)
				)
			)
		)
		(property "Device Type" "C603H36"
			(at 0 -4.3434 180)
			(unlocked yes)
			(layer "F.Fab")
			(hide yes)
			(effects
				(font
					(size 1.016 1.016)
					(thickness 0.1524)
				)
			)
		)
		(duplicate_pad_numbers_are_jumpers no)
		(fp_line
			(start 0.508 0)
			(end -0.508 0)
			(stroke
				(width 0.2032)
				(type default)
			)
			(layer "F.SilkS")
		)
		(fp_rect
			(start -0.5842 1.3335)
			(end 0.5842 -1.3335)
			(stroke
				(width 0)
				(type default)
			)
			(fill no)
			(layer "F.CrtYd")
		)
		(fp_rect
			(start -0.5842 1.3335)
			(end 0.5842 -1.3335)
			(stroke
				(width 0)
				(type default)
			)
			(fill no)
			(layer "F.Fab")
		)
		(pad "1" smd custom
			(at 0 -0.762 180)
			(size 0.2159 0.2159)
			(layers "F.Cu" "F.Mask" "F.Paste")
			(net "P12V_SSD7")
			(options
				(clearance outline)
				(anchor circle)
			)
			(primitives
				(gr_poly
					(pts
						(arc
							(start -0.3302 -0.4318)
							(mid -0.402042 -0.402042)
							(end -0.4318 -0.3302)
						)
						(arc
							(start -0.4318 0.3302)
							(mid -0.402042 0.402042)
							(end -0.3302 0.4318)
						)
						(arc
							(start 0.3302 0.4318)
							(mid 0.402042 0.402042)
							(end 0.4318 0.3302)
						)
						(arc
							(start 0.4318 -0.3302)
							(mid 0.402042 -0.402042)
							(end 0.3302 -0.4318)
						)
					)
					(width 0)
					(fill yes)
				)
			)
		)
		(pad "2" smd custom
			(at 0 0.762 180)
			(size 0.2159 0.2159)
			(layers "F.Cu" "F.Mask" "F.Paste")
			(net "GND")
			(options
				(clearance outline)
				(anchor circle)
			)
			(primitives
				(gr_poly
					(pts
						(arc
							(start -0.3302 -0.4318)
							(mid -0.402042 -0.402042)
							(end -0.4318 -0.3302)
						)
						(arc
							(start -0.4318 0.3302)
							(mid -0.402042 0.402042)
							(end -0.3302 0.4318)
						)
						(arc
							(start 0.3302 0.4318)
							(mid 0.402042 0.402042)
							(end 0.4318 0.3302)
						)
						(arc
							(start 0.4318 -0.3302)
							(mid 0.402042 -0.402042)
							(end 0.3302 -0.4318)
						)
					)
					(width 0)
					(fill yes)
				)
			)
		)
	)
	(footprint ""
		(layer "F.Cu")
		(at 214.9348 -187.579)
		(property "Reference" "SR1097"
			(at 0 0 0)
			(layer "F.SilkS")
			(hide yes)
			(effects
				(font
					(size 1.27 1.27)
				)
			)
		)
		(property "Value" "4K7R2F-GP"
			(at 0.064008 -3.993896 0)
			(unlocked yes)
			(layer "F.Fab")
			(hide yes)
			(effects
				(font
					(size 1.016 1.016)
					(thickness 0.1524)
				)
			)
		)
		(property "Device Type" "R402H16"
			(at 0.064008 -5.517896 0)
			(unlocked yes)
			(layer "F.Fab")
			(hide yes)
			(effects
				(font
					(size 1.016 1.016)
					(thickness 0.1524)
				)
			)
		)
		(duplicate_pad_numbers_are_jumpers no)
		(fp_line
			(start -0.508 -0.9398)
			(end -0.508 0.9398)
			(stroke
				(width 0.1524)
				(type default)
			)
			(layer "F.SilkS")
		)
		(fp_line
			(start 0.508 -0.9398)
			(end -0.508 -0.9398)
			(stroke
				(width 0.1524)
				(type default)
			)
			(layer "F.SilkS")
		)
		(fp_rect
			(start -0.508 0.9398)
			(end 0.508 -0.9398)
			(stroke
				(width 0)
				(type default)
			)
			(fill no)
			(layer "F.CrtYd")
		)
		(fp_rect
			(start -0.508 0.9398)
			(end 0.508 -0.9398)
			(stroke
				(width 0)
				(type default)
			)
			(fill no)
			(layer "F.Fab")
		)
		(pad "1" smd custom
			(at 0 -0.4445)
			(size 0.1397 0.1397)
			(layers "F.Cu" "F.Mask" "F.Paste")
			(net "P3V3")
			(options
				(clearance outline)
				(anchor circle)
			)
			(primitives
				(gr_poly
					(pts
						(arc
							(start -0.1778 -0.2794)
							(mid -0.249642 -0.249642)
							(end -0.2794 -0.1778)
						)
						(arc
							(start -0.2794 0.1778)
							(mid -0.249642 0.249642)
							(end -0.1778 0.2794)
						)
						(arc
							(start 0.1778 0.2794)
							(mid 0.249642 0.249642)
							(end 0.2794 0.1778)
						)
						(arc
							(start 0.2794 -0.1778)
							(mid 0.249642 -0.249642)
							(end 0.1778 -0.2794)
						)
					)
					(width 0)
					(fill yes)
				)
			)
		)
		(pad "2" smd custom
			(at 0 0.4445)
			(size 0.1397 0.1397)
			(layers "F.Cu" "F.Mask" "F.Paste")
			(net "DUALPORTEN#3")
			(options
				(clearance outline)
				(anchor circle)
			)
			(primitives
				(gr_poly
					(pts
						(arc
							(start -0.1778 -0.2794)
							(mid -0.249642 -0.249642)
							(end -0.2794 -0.1778)
						)
						(arc
							(start -0.2794 0.1778)
							(mid -0.249642 0.249642)
							(end -0.1778 0.2794)
						)
						(arc
							(start 0.1778 0.2794)
							(mid 0.249642 0.249642)
							(end 0.2794 0.1778)
						)
						(arc
							(start 0.2794 -0.1778)
							(mid 0.249642 -0.249642)
							(end 0.1778 -0.2794)
						)
					)
					(width 0)
					(fill yes)
				)
			)
		)
	)
	(footprint ""
		(layer "F.Cu")
		(at 211.582 -51.562 -90)
		(property "Reference" "C342"
			(at 0 0 270)
			(layer "F.SilkS")
			(hide yes)
			(effects
				(font
					(size 1.27 1.27)
				)
			)
		)
		(property "Value" "SCD1U16V2KX-3GP"
			(at 1.1811 -2.7051 270)
			(unlocked yes)
			(layer "F.Fab")
			(hide yes)
			(effects
				(font
					(size 1.016 1.016)
					(thickness 0.1524)
				)
			)
		)
		(property "Device Type" "C402H22"
			(at 1.1811 -4.2291 270)
			(unlocked yes)
			(layer "F.Fab")
			(hide yes)
			(effects
				(font
					(size 1.016 1.016)
					(thickness 0.1524)
				)
			)
		)
		(duplicate_pad_numbers_are_jumpers no)
		(fp_rect
			(start -0.4318 0.9525)
			(end 0.4318 -0.9525)
			(stroke
				(width 0)
				(type default)
			)
			(fill no)
			(layer "F.CrtYd")
		)
		(fp_rect
			(start -0.4318 0.9525)
			(end 0.4318 -0.9525)
			(stroke
				(width 0)
				(type default)
			)
			(fill no)
			(layer "F.Fab")
		)
		(pad "1" smd custom
			(at 0 -0.4445 270)
			(size 0.1524 0.1524)
			(layers "F.Cu" "F.Mask" "F.Paste")
			(net "P3V3")
			(options
				(clearance outline)
				(anchor circle)
			)
			(primitives
				(gr_poly
					(pts
						(arc
							(start 0.3048 -0.2032)
							(mid 0.275042 -0.275042)
							(end 0.2032 -0.3048)
						)
						(arc
							(start -0.2032 -0.3048)
							(mid -0.275042 -0.275042)
							(end -0.3048 -0.2032)
						)
						(arc
							(start -0.3048 0.2032)
							(mid -0.275042 0.275042)
							(end -0.2032 0.3048)
						)
						(arc
							(start 0.2032 0.3048)
							(mid 0.275042 0.275042)
							(end 0.3048 0.2032)
						)
					)
					(width 0)
					(fill yes)
				)
			)
		)
		(pad "2" smd custom
			(at 0 0.4445 270)
			(size 0.1524 0.1524)
			(layers "F.Cu" "F.Mask" "F.Paste")
			(net "GND")
			(options
				(clearance outline)
				(anchor circle)
			)
			(primitives
				(gr_poly
					(pts
						(arc
							(start 0.3048 -0.2032)
							(mid 0.275042 -0.275042)
							(end 0.2032 -0.3048)
						)
						(arc
							(start -0.2032 -0.3048)
							(mid -0.275042 -0.275042)
							(end -0.3048 -0.2032)
						)
						(arc
							(start -0.3048 0.2032)
							(mid -0.275042 0.275042)
							(end -0.2032 0.3048)
						)
						(arc
							(start 0.2032 0.3048)
							(mid 0.275042 0.275042)
							(end 0.3048 0.2032)
						)
					)
					(width 0)
					(fill yes)
				)
			)
		)
	)
	(footprint ""
		(layer "F.Cu")
		(at 7.6708 -378.4854 180)
		(property "Reference" "C9535"
			(at 0 0 180)
			(layer "F.SilkS")
			(hide yes)
			(effects
				(font
					(size 1.27 1.27)
				)
			)
		)
		(property "Value" "SCD01U50V2KX-1GP"
			(at 1.1811 -2.7051 180)
			(unlocked yes)
			(layer "F.Fab")
			(hide yes)
			(effects
				(font
					(size 1.016 1.016)
					(thickness 0.1524)
				)
			)
		)
		(property "Device Type" "C402H22"
			(at 1.1811 -4.2291 180)
			(unlocked yes)
			(layer "F.Fab")
			(hide yes)
			(effects
				(font
					(size 1.016 1.016)
					(thickness 0.1524)
				)
			)
		)
		(duplicate_pad_numbers_are_jumpers no)
		(fp_rect
			(start -0.4318 0.9525)
			(end 0.4318 -0.9525)
			(stroke
				(width 0)
				(type default)
			)
			(fill no)
			(layer "F.CrtYd")
		)
		(fp_rect
			(start -0.4318 0.9525)
			(end 0.4318 -0.9525)
			(stroke
				(width 0)
				(type default)
			)
			(fill no)
			(layer "F.Fab")
		)
		(pad "1" smd custom
			(at 0 -0.4445 180)
			(size 0.1524 0.1524)
			(layers "F.Cu" "F.Mask" "F.Paste")
			(net "PE_100M_CLK1_P")
			(options
				(clearance outline)
				(anchor circle)
			)
			(primitives
				(gr_poly
					(pts
						(arc
							(start 0.3048 -0.2032)
							(mid 0.275042 -0.275042)
							(end 0.2032 -0.3048)
						)
						(arc
							(start -0.2032 -0.3048)
							(mid -0.275042 -0.275042)
							(end -0.3048 -0.2032)
						)
						(arc
							(start -0.3048 0.2032)
							(mid -0.275042 0.275042)
							(end -0.2032 0.3048)
						)
						(arc
							(start 0.2032 0.3048)
							(mid 0.275042 0.275042)
							(end 0.3048 0.2032)
						)
					)
					(width 0)
					(fill yes)
				)
			)
		)
		(pad "2" smd custom
			(at 0 0.4445 180)
			(size 0.1524 0.1524)
			(layers "F.Cu" "F.Mask" "F.Paste")
			(net "PE_100M_CLK1_C_P")
			(options
				(clearance outline)
				(anchor circle)
			)
			(primitives
				(gr_poly
					(pts
						(arc
							(start 0.3048 -0.2032)
							(mid 0.275042 -0.275042)
							(end 0.2032 -0.3048)
						)
						(arc
							(start -0.2032 -0.3048)
							(mid -0.275042 -0.275042)
							(end -0.3048 -0.2032)
						)
						(arc
							(start -0.3048 0.2032)
							(mid -0.275042 0.275042)
							(end -0.2032 0.3048)
						)
						(arc
							(start 0.2032 0.3048)
							(mid 0.275042 0.275042)
							(end 0.3048 0.2032)
						)
					)
					(width 0)
					(fill yes)
				)
			)
		)
	)
)
